# BASEBOARD_FAB2 (Tioga Pass) — schematic netlist excerpt (pin names and nets, part order shuffled) for the footprints in the layout excerpt that follows; sources: Cadence DE-HDL packaged netlist, KiCad conversion of Wiwynn_Tioga_Pass_MB.brd

C7G8  CAP  0.22UF 16V 10% X7R  pkg 0402  page 105 : A = P3E_CPU0_PE2_SS_TXP<14> ; B = P3E_CPU0_PE2_SS_C_TXP<14>
C5D3  CAP_A  22.0UF 4V 20% X6S  pkg 0603V  page 220 : A = PVDDQ_DEF ; B = GND

(kicad_pcb
	(version 20260206)
	(generator "pcbnew")
	(generator_version "10.0")
	(general
		(thickness 1.6)
		(legacy_teardrops no)
	)
	(paper "A4")
	(title_block
		(title "Wiwynn_Tioga_Pass_MB.brd")
		(comment 1 "Tioga Pass / footprints 777-779 of 4770")
	)
	(layers
		(0 "F.Cu" signal "TOP")
		(4 "In1.Cu" signal "L2GND")
		(6 "In2.Cu" signal "L3")
		(8 "In3.Cu" signal "L4GND")
		(10 "In4.Cu" signal "L5")
		(12 "In5.Cu" signal "L6GND")
		(14 "In6.Cu" signal "L7VCC")
		(16 "In7.Cu" signal "L8VCC")
		(18 "In8.Cu" signal "L9GND")
		(20 "In9.Cu" signal "L10")
		(22 "In10.Cu" signal "L11GND")
		(24 "In11.Cu" signal "L12")
		(26 "In12.Cu" signal "L13GND")
		(2 "B.Cu" signal "BOTTOM")
		(9 "F.Adhes" user "F.Adhesive")
		(11 "B.Adhes" user "B.Adhesive")
		(13 "F.Paste" user "Package Geometry/Pastemask Top")
		(15 "B.Paste" user "Package Geometry/Pastemask Bottom")
		(5 "F.SilkS" user "Ref Des/Silkscreen Top")
		(7 "B.SilkS" user "Ref Des/Silkscreen Bottom")
		(1 "F.Mask" user "Board Geometry/Soldermask Top")
		(3 "B.Mask" user "Board Geometry/Soldermask Bottom")
		(17 "Dwgs.User" user "User.Drawings")
		(19 "Cmts.User" user "User.Comments")
		(21 "Eco1.User" user "User.Eco1")
		(23 "Eco2.User" user "User.Eco2")
		(25 "Edge.Cuts" user "Board Geometry/Outline")
		(27 "Margin" user)
		(31 "F.CrtYd" user "Package Geometry/Place Bound Top")
		(29 "B.CrtYd" user "Package Geometry/Place Bound Bottom")
		(35 "F.Fab" user "Ref Des/Assembly Top")
		(33 "B.Fab" user "Ref Des/Assembly Bottom")
	)
	(footprint ""
		(layer "F.Cu")
		(at 270.99641 -84.890102)
		(property "Reference" "C5D3"
			(at 0 0 0)
			(layer "F.SilkS")
			(hide yes)
			(effects
				(font
					(size 1.27 1.27)
				)
			)
		)
		(property "Value" ""
			(at 0 0 0)
			(layer "F.Fab")
			(effects
				(font
					(size 1.27 1.27)
				)
			)
		)
		(duplicate_pad_numbers_are_jumpers no)
		(fp_poly
			(pts
				(xy -0.4953 -0.2032) (xy 0.4953 -0.2032) (xy 0.4953 1.6002) (xy -0.4953 1.6002)
			)
			(stroke
				(width 0)
				(type default)
			)
			(fill no)
			(layer "F.CrtYd")
		)
		(fp_line
			(start -0.4953 -0.2032)
			(end 0.4953 -0.2032)
			(stroke
				(width 0.1)
				(type default)
			)
			(layer "F.Fab")
		)
		(fp_line
			(start -0.4953 1.6002)
			(end -0.4953 -0.2032)
			(stroke
				(width 0.1)
				(type default)
			)
			(layer "F.Fab")
		)
		(fp_line
			(start 0.4953 -0.2032)
			(end 0.4953 1.6002)
			(stroke
				(width 0.1)
				(type default)
			)
			(layer "F.Fab")
		)
		(fp_line
			(start 0.4953 1.6002)
			(end -0.4953 1.6002)
			(stroke
				(width 0.1)
				(type default)
			)
			(layer "F.Fab")
		)
		(pad "1" smd rect
			(at 0 0)
			(size 0.762 0.889)
			(layers "F.Cu" "F.Mask" "F.Paste")
			(net "PVDDQ_DEF")
		)
		(pad "2" smd rect
			(at 0 1.397)
			(size 0.762 0.889)
			(layers "F.Cu" "F.Mask" "F.Paste")
			(net "GND")
		)
		(zone
			(layer "F.Cu")
			(hatch none 0.5)
			(connect_pads
				(clearance 0)
			)
			(min_thickness 0.25)
			(keepout
				(tracks not_allowed)
				(vias allowed)
				(pads allowed)
				(copperpour not_allowed)
				(footprints allowed)
			)
			(placement
				(enabled no)
				(sheetname "")
			)
			(fill
				(thermal_gap 0.5)
				(thermal_bridge_width 0.5)
				(island_removal_mode 0)
			)
			(polygon
				(pts
					(xy 270.61541 -84.445602) (xy 271.37741 -84.445602) (xy 271.37741 -83.937602) (xy 270.61541 -83.937602)
				)
			)
		)
	)
	(footprint ""
		(layer "F.Cu")
		(at 365.489744 -10.916158)
		(property "Reference" "C7G8"
			(at 0 0 0)
			(layer "F.SilkS")
			(hide yes)
			(effects
				(font
					(size 1.27 1.27)
				)
			)
		)
		(property "Value" ""
			(at 0 0 0)
			(layer "F.Fab")
			(effects
				(font
					(size 1.27 1.27)
				)
			)
		)
		(duplicate_pad_numbers_are_jumpers no)
		(fp_rect
			(start -0.3048 0.9906)
			(end 0.3048 -0.1016)
			(stroke
				(width 0)
				(type default)
			)
			(fill no)
			(layer "F.CrtYd")
		)
		(fp_line
			(start -0.3048 -0.1016)
			(end -0.3048 0.9906)
			(stroke
				(width 0.1)
				(type default)
			)
			(layer "F.Fab")
		)
		(fp_line
			(start -0.3048 0.9906)
			(end 0.3048 0.9906)
			(stroke
				(width 0.1)
				(type default)
			)
			(layer "F.Fab")
		)
		(fp_line
			(start 0.3048 -0.1016)
			(end -0.3048 -0.1016)
			(stroke
				(width 0.1)
				(type default)
			)
			(layer "F.Fab")
		)
		(fp_line
			(start 0.3048 0.9906)
			(end 0.3048 -0.1016)
			(stroke
				(width 0.1)
				(type default)
			)
			(layer "F.Fab")
		)
		(pad "1" smd rect
			(at 0 0)
			(size 0.508 0.508)
			(layers "F.Cu" "F.Mask" "F.Paste")
			(net "P3E_CPU0_PE2_SS_TXP<14>")
		)
		(pad "2" smd rect
			(at 0 0.889)
			(size 0.508 0.508)
			(layers "F.Cu" "F.Mask" "F.Paste")
			(net "P3E_CPU0_PE2_SS_C_TXP<14>")
		)
		(zone
			(layer "F.Cu")
			(hatch none 0.5)
			(connect_pads
				(clearance 0)
			)
			(min_thickness 0.25)
			(keepout
				(tracks allowed)
				(vias not_allowed)
				(pads allowed)
				(copperpour not_allowed)
				(footprints allowed)
			)
			(placement
				(enabled no)
				(sheetname "")
			)
			(fill
				(thermal_gap 0.5)
				(thermal_bridge_width 0.5)
				(island_removal_mode 0)
			)
			(polygon
				(pts
					(xy 365.235744 -10.281158) (xy 365.743744 -10.281158) (xy 365.743744 -10.662158) (xy 365.235744 -10.662158)
				)
			)
		)
		(zone
			(layer "F.Cu")
			(hatch none 0.5)
			(connect_pads
				(clearance 0)
			)
			(min_thickness 0.25)
			(keepout
				(tracks not_allowed)
				(vias allowed)
				(pads allowed)
				(copperpour not_allowed)
				(footprints allowed)
			)
			(placement
				(enabled no)
				(sheetname "")
			)
			(fill
				(thermal_gap 0.5)
				(thermal_bridge_width 0.5)
				(island_removal_mode 0)
			)
			(polygon
				(pts
					(xy 365.235744 -10.281158) (xy 365.743744 -10.281158) (xy 365.743744 -10.662158) (xy 365.235744 -10.662158)
				)
			)
		)
	)
	(footprint ""
		(layer "F.Cu")
		(at 34.71418 -40.59936)
		(property "Reference" ""
			(at 0 0 0)
			(layer "F.SilkS")
			(hide yes)
			(effects
				(font
					(size 1.27 1.27)
				)
			)
		)
		(property "Value" ""
			(at 0 0 0)
			(layer "F.Fab")
			(effects
				(font
					(size 1.27 1.27)
				)
			)
		)
		(duplicate_pad_numbers_are_jumpers no)
		(fp_poly
			(pts
				(arc
					(start 2.032 0)
					(mid -2.032 0)
					(end 2.032 0)
				)
			)
			(stroke
				(width 0)
				(type default)
			)
			(fill no)
			(layer "F.CrtYd")
		)
		(pad "1" smd circle
			(at 0 0)
			(size 1.016 1.016)
			(layers "F.Cu" "F.Mask" "F.Paste")
			(net "Net_304")
		)
		(zone
			(layer "F.Cu")
			(hatch none 0.5)
			(connect_pads
				(clearance 0)
			)
			(min_thickness 0.25)
			(keepout
				(tracks not_allowed)
				(vias allowed)
				(pads allowed)
				(copperpour not_allowed)
				(footprints allowed)
			)
			(placement
				(enabled no)
				(sheetname "")
			)
			(fill
				(thermal_gap 0.5)
				(thermal_bridge_width 0.5)
				(island_removal_mode 0)
			)
			(polygon
				(pts
					(arc
						(start 36.23818 -40.59936)
						(mid 33.19018 -40.59936)
						(end 36.23818 -40.59936)
					)
				)
			)
		)
		(zone
			(layers "F.Cu" "B.Cu" "In1.Cu" "In2.Cu" "In3.Cu" "In4.Cu" "In5.Cu" "In6.Cu"
				"In7.Cu" "In8.Cu" "In9.Cu" "In10.Cu" "In11.Cu" "In12.Cu"
			)
			(hatch none 0.5)
			(connect_pads
				(clearance 0)
			)
			(min_thickness 0.25)
			(keepout
				(tracks allowed)
				(vias not_allowed)
				(pads allowed)
				(copperpour not_allowed)
				(footprints allowed)
			)
			(placement
				(enabled no)
				(sheetname "")
			)
			(fill
				(thermal_gap 0.5)
				(thermal_bridge_width 0.5)
				(island_removal_mode 0)
			)
			(polygon
				(pts
					(arc
						(start 36.23818 -40.59936)
						(mid 33.19018 -40.59936)
						(end 36.23818 -40.59936)
					)
				)
			)
		)
	)
)
